(kicad_pcb
	(version 20260206)
	(generator "pcbnew")
	(generator_version "10.0")
	(general
		(thickness 1.6)
		(legacy_teardrops no)
	)
	(paper "A4")
	(title_block
		(title "03242023_DA0F0TMBIJ0_F0T_Motherboard_J_brd_V01_OCP.brd")
		(comment 1 "Grand Teton / footprints 3633-3639 of 6105")
	)
	(layers
		(0 "F.Cu" signal "TOP")
		(4 "In1.Cu" signal "GND")
		(6 "In2.Cu" signal "IN1")
		(8 "In3.Cu" signal "GND1")
		(10 "In4.Cu" signal "IN2")
		(12 "In5.Cu" signal "GND2")
		(14 "In6.Cu" signal "IN3")
		(16 "In7.Cu" signal "GND3")
		(18 "In8.Cu" signal "VCC")
		(20 "In9.Cu" signal "VCC1")
		(22 "In10.Cu" signal "GND4")
		(24 "In11.Cu" signal "IN4")
		(26 "In12.Cu" signal "GND5")
		(28 "In13.Cu" signal "IN5")
		(30 "In14.Cu" signal "GND6")
		(32 "In15.Cu" signal "IN6")
		(34 "In16.Cu" signal "GND7")
		(2 "B.Cu" signal "BOTTOM")
		(9 "F.Adhes" user "F.Adhesive")
		(11 "B.Adhes" user "B.Adhesive")
		(13 "F.Paste" user "Package Geometry/Pastemask Top")
		(15 "B.Paste" user "Package Geometry/Pastemask Bottom")
		(5 "F.SilkS" user "Ref Des/Silkscreen Top")
		(7 "B.SilkS" user "Ref Des/Silkscreen Bottom")
		(1 "F.Mask" user "Board Geometry/Soldermask Top")
		(3 "B.Mask" user "Board Geometry/Soldermask Bottom")
		(17 "Dwgs.User" user "User.Drawings")
		(19 "Cmts.User" user "User.Comments")
		(21 "Eco1.User" user "User.Eco1")
		(23 "Eco2.User" user "User.Eco2")
		(25 "Edge.Cuts" user "Board Geometry/Outline")
		(27 "Margin" user)
		(31 "F.CrtYd" user "Package Geometry/Place Bound Top")
		(29 "B.CrtYd" user "Package Geometry/Place Bound Bottom")
		(35 "F.Fab" user "Ref Des/Assembly Top")
		(33 "B.Fab" user "Ref Des/Assembly Bottom")
	)
	(footprint ""
		(layer "F.Cu")
		(at 346.995496 -26.804366 -90)
		(property "Reference" "R1024"
			(at 0 0 270)
			(layer "F.SilkS")
			(hide yes)
			(effects
				(font
					(size 1.27 1.27)
				)
			)
		)
		(property "Value" ""
			(at 0 0 270)
			(layer "F.Fab")
			(effects
				(font
					(size 1.27 1.27)
				)
			)
		)
		(duplicate_pad_numbers_are_jumpers no)
		(fp_line
			(start -0.7874 0.4064)
			(end -0.7874 -0.4064)
			(stroke
				(width 0.1524)
				(type default)
			)
			(layer "F.SilkS")
		)
		(fp_line
			(start 0.7874 0.4064)
			(end -0.7874 0.4064)
			(stroke
				(width 0.1524)
				(type default)
			)
			(layer "F.SilkS")
		)
		(fp_line
			(start -0.7874 -0.4064)
			(end 0.7874 -0.4064)
			(stroke
				(width 0.1524)
				(type default)
			)
			(layer "F.SilkS")
		)
		(fp_line
			(start 0.7874 -0.4064)
			(end 0.7874 0.4064)
			(stroke
				(width 0.1524)
				(type default)
			)
			(layer "F.SilkS")
		)
		(fp_line
			(start -0.67945 0.3048)
			(end -0.67945 -0.305054)
			(stroke
				(width 0.1)
				(type default)
			)
			(layer "F.Fab")
		)
		(fp_line
			(start -0.12065 0.3048)
			(end -0.67945 0.3048)
			(stroke
				(width 0.1)
				(type default)
			)
			(layer "F.Fab")
		)
		(fp_line
			(start 0.120396 0.3048)
			(end 0.120396 0.2794)
			(stroke
				(width 0.1)
				(type default)
			)
			(layer "F.Fab")
		)
		(fp_line
			(start 0.67945 0.3048)
			(end 0.120396 0.3048)
			(stroke
				(width 0.1)
				(type default)
			)
			(layer "F.Fab")
		)
		(fp_line
			(start -0.12065 0.2794)
			(end -0.12065 0.3048)
			(stroke
				(width 0.1)
				(type default)
			)
			(layer "F.Fab")
		)
		(fp_line
			(start 0.120396 0.2794)
			(end -0.12065 0.2794)
			(stroke
				(width 0.1)
				(type default)
			)
			(layer "F.Fab")
		)
		(fp_line
			(start -0.12065 -0.2794)
			(end 0.12065 -0.2794)
			(stroke
				(width 0.1)
				(type default)
			)
			(layer "F.Fab")
		)
		(fp_line
			(start 0.12065 -0.2794)
			(end 0.12065 -0.3048)
			(stroke
				(width 0.1)
				(type default)
			)
			(layer "F.Fab")
		)
		(fp_line
			(start 0.12065 -0.3048)
			(end 0.67945 -0.3048)
			(stroke
				(width 0.1)
				(type default)
			)
			(layer "F.Fab")
		)
		(fp_line
			(start 0.67945 -0.3048)
			(end 0.67945 0.3048)
			(stroke
				(width 0.1)
				(type default)
			)
			(layer "F.Fab")
		)
		(fp_line
			(start -0.67945 -0.305054)
			(end -0.12065 -0.305054)
			(stroke
				(width 0.1)
				(type default)
			)
			(layer "F.Fab")
		)
		(fp_line
			(start -0.12065 -0.305054)
			(end -0.12065 -0.2794)
			(stroke
				(width 0.1)
				(type default)
			)
			(layer "F.Fab")
		)
		(pad "1" smd circle
			(at -0.40005 0 270)
			(size 0 0)
			(layers "F.Cu" "F.Mask" "F.Paste")
			(net "JTAG_DBP_TCK_PCH")
		)
		(pad "2" smd circle
			(at 0.40005 0 270)
			(size 0 0)
			(layers "F.Cu" "F.Mask" "F.Paste")
			(net "GND")
		)
	)
	(footprint ""
		(layer "F.Cu")
		(at 93.100398 -408.517344 -90)
		(property "Reference" "C681"
			(at 0 0 270)
			(layer "F.SilkS")
			(hide yes)
			(effects
				(font
					(size 1.27 1.27)
				)
			)
		)
		(property "Value" ""
			(at 0 0 270)
			(layer "F.Fab")
			(effects
				(font
					(size 1.27 1.27)
				)
			)
		)
		(duplicate_pad_numbers_are_jumpers no)
		(fp_line
			(start -0.299974 0.150114)
			(end -0.299974 -0.150114)
			(stroke
				(width 0.1)
				(type default)
			)
			(layer "F.Fab")
		)
		(fp_line
			(start 0.299974 0.150114)
			(end -0.299974 0.150114)
			(stroke
				(width 0.1)
				(type default)
			)
			(layer "F.Fab")
		)
		(fp_line
			(start -0.299974 -0.150114)
			(end 0.299974 -0.150114)
			(stroke
				(width 0.1)
				(type default)
			)
			(layer "F.Fab")
		)
		(fp_line
			(start 0.299974 -0.150114)
			(end 0.299974 0.150114)
			(stroke
				(width 0.1)
				(type default)
			)
			(layer "F.Fab")
		)
		(pad "1" smd rect
			(at -0.2667 0 270)
			(size 0.3048 0.381)
			(layers "F.Cu" "F.Mask" "F.Paste")
			(net "P5E_CPU1_PE4_TX_C_DP<14>")
		)
		(pad "2" smd rect
			(at 0.2667 0 270)
			(size 0.3048 0.381)
			(layers "F.Cu" "F.Mask" "F.Paste")
			(net "P5E_CPU1_PE4_TX_DP<14>")
		)
	)
	(footprint ""
		(layer "F.Cu")
		(at 364.50143 -252.956314 -90)
		(property "Reference" "C1016"
			(at 0 0 270)
			(layer "F.SilkS")
			(hide yes)
			(effects
				(font
					(size 1.27 1.27)
				)
			)
		)
		(property "Value" ""
			(at 0 0 270)
			(layer "F.Fab")
			(effects
				(font
					(size 1.27 1.27)
				)
			)
		)
		(duplicate_pad_numbers_are_jumpers no)
		(fp_line
			(start -0.7874 0.4064)
			(end -0.7874 -0.4064)
			(stroke
				(width 0.1524)
				(type default)
			)
			(layer "F.SilkS")
		)
		(fp_line
			(start 0.7874 0.4064)
			(end -0.7874 0.4064)
			(stroke
				(width 0.1524)
				(type default)
			)
			(layer "F.SilkS")
		)
		(fp_line
			(start -0.7874 -0.4064)
			(end 0.7874 -0.4064)
			(stroke
				(width 0.1524)
				(type default)
			)
			(layer "F.SilkS")
		)
		(fp_line
			(start 0.7874 -0.4064)
			(end 0.7874 0.4064)
			(stroke
				(width 0.1524)
				(type default)
			)
			(layer "F.SilkS")
		)
		(fp_line
			(start -0.67945 0.3048)
			(end -0.67945 -0.305054)
			(stroke
				(width 0.1)
				(type default)
			)
			(layer "F.Fab")
		)
		(fp_line
			(start -0.12065 0.3048)
			(end -0.67945 0.3048)
			(stroke
				(width 0.1)
				(type default)
			)
			(layer "F.Fab")
		)
		(fp_line
			(start 0.120396 0.3048)
			(end 0.120396 0.2794)
			(stroke
				(width 0.1)
				(type default)
			)
			(layer "F.Fab")
		)
		(fp_line
			(start 0.67945 0.3048)
			(end 0.120396 0.3048)
			(stroke
				(width 0.1)
				(type default)
			)
			(layer "F.Fab")
		)
		(fp_line
			(start -0.12065 0.2794)
			(end -0.12065 0.3048)
			(stroke
				(width 0.1)
				(type default)
			)
			(layer "F.Fab")
		)
		(fp_line
			(start 0.120396 0.2794)
			(end -0.12065 0.2794)
			(stroke
				(width 0.1)
				(type default)
			)
			(layer "F.Fab")
		)
		(fp_line
			(start -0.12065 -0.2794)
			(end 0.12065 -0.2794)
			(stroke
				(width 0.1)
				(type default)
			)
			(layer "F.Fab")
		)
		(fp_line
			(start 0.12065 -0.2794)
			(end 0.12065 -0.3048)
			(stroke
				(width 0.1)
				(type default)
			)
			(layer "F.Fab")
		)
		(fp_line
			(start 0.12065 -0.3048)
			(end 0.67945 -0.3048)
			(stroke
				(width 0.1)
				(type default)
			)
			(layer "F.Fab")
		)
		(fp_line
			(start 0.67945 -0.3048)
			(end 0.67945 0.3048)
			(stroke
				(width 0.1)
				(type default)
			)
			(layer "F.Fab")
		)
		(fp_line
			(start -0.67945 -0.305054)
			(end -0.12065 -0.305054)
			(stroke
				(width 0.1)
				(type default)
			)
			(layer "F.Fab")
		)
		(fp_line
			(start -0.12065 -0.305054)
			(end -0.12065 -0.2794)
			(stroke
				(width 0.1)
				(type default)
			)
			(layer "F.Fab")
		)
		(pad "1" smd circle
			(at -0.40005 0 270)
			(size 0 0)
			(layers "F.Cu" "F.Mask" "F.Paste")
			(net "PVCCIN_CPU0")
		)
		(pad "2" smd circle
			(at 0.40005 0 270)
			(size 0 0)
			(layers "F.Cu" "F.Mask" "F.Paste")
			(net "GND")
		)
	)
	(footprint ""
		(layer "F.Cu")
		(at 45.136308 -353.61626 -90)
		(property "Reference" "PC1196_P1_4"
			(at 0 0 270)
			(layer "F.SilkS")
			(hide yes)
			(effects
				(font
					(size 1.27 1.27)
				)
			)
		)
		(property "Value" ""
			(at 0 0 270)
			(layer "F.Fab")
			(effects
				(font
					(size 1.27 1.27)
				)
			)
		)
		(duplicate_pad_numbers_are_jumpers no)
		(fp_line
			(start -0.7874 0.4064)
			(end -0.7874 -0.4064)
			(stroke
				(width 0.1524)
				(type default)
			)
			(layer "F.SilkS")
		)
		(fp_line
			(start 0.7874 0.4064)
			(end -0.7874 0.4064)
			(stroke
				(width 0.1524)
				(type default)
			)
			(layer "F.SilkS")
		)
		(fp_line
			(start -0.7874 -0.4064)
			(end 0.7874 -0.4064)
			(stroke
				(width 0.1524)
				(type default)
			)
			(layer "F.SilkS")
		)
		(fp_line
			(start 0.7874 -0.4064)
			(end 0.7874 0.4064)
			(stroke
				(width 0.1524)
				(type default)
			)
			(layer "F.SilkS")
		)
		(fp_line
			(start -0.67945 0.3048)
			(end -0.67945 -0.305054)
			(stroke
				(width 0.1)
				(type default)
			)
			(layer "F.Fab")
		)
		(fp_line
			(start -0.12065 0.3048)
			(end -0.67945 0.3048)
			(stroke
				(width 0.1)
				(type default)
			)
			(layer "F.Fab")
		)
		(fp_line
			(start 0.120396 0.3048)
			(end 0.120396 0.2794)
			(stroke
				(width 0.1)
				(type default)
			)
			(layer "F.Fab")
		)
		(fp_line
			(start 0.67945 0.3048)
			(end 0.120396 0.3048)
			(stroke
				(width 0.1)
				(type default)
			)
			(layer "F.Fab")
		)
		(fp_line
			(start -0.12065 0.2794)
			(end -0.12065 0.3048)
			(stroke
				(width 0.1)
				(type default)
			)
			(layer "F.Fab")
		)
		(fp_line
			(start 0.120396 0.2794)
			(end -0.12065 0.2794)
			(stroke
				(width 0.1)
				(type default)
			)
			(layer "F.Fab")
		)
		(fp_line
			(start -0.12065 -0.2794)
			(end 0.12065 -0.2794)
			(stroke
				(width 0.1)
				(type default)
			)
			(layer "F.Fab")
		)
		(fp_line
			(start 0.12065 -0.2794)
			(end 0.12065 -0.3048)
			(stroke
				(width 0.1)
				(type default)
			)
			(layer "F.Fab")
		)
		(fp_line
			(start 0.12065 -0.3048)
			(end 0.67945 -0.3048)
			(stroke
				(width 0.1)
				(type default)
			)
			(layer "F.Fab")
		)
		(fp_line
			(start 0.67945 -0.3048)
			(end 0.67945 0.3048)
			(stroke
				(width 0.1)
				(type default)
			)
			(layer "F.Fab")
		)
		(fp_line
			(start -0.67945 -0.305054)
			(end -0.12065 -0.305054)
			(stroke
				(width 0.1)
				(type default)
			)
			(layer "F.Fab")
		)
		(fp_line
			(start -0.12065 -0.305054)
			(end -0.12065 -0.2794)
			(stroke
				(width 0.1)
				(type default)
			)
			(layer "F.Fab")
		)
		(pad "1" smd circle
			(at -0.40005 0 270)
			(size 0 0)
			(layers "F.Cu" "F.Mask" "F.Paste")
			(net "SW_P12V_PVCCFA_EHV_FIVRA_CPU1_L")
		)
		(pad "2" smd circle
			(at 0.40005 0 270)
			(size 0 0)
			(layers "F.Cu" "F.Mask" "F.Paste")
			(net "GND")
		)
	)
	(footprint ""
		(layer "F.Cu")
		(at 151.5872 -127.897128 90)
		(property "Reference" "C1825"
			(at 0 0 90)
			(layer "F.SilkS")
			(hide yes)
			(effects
				(font
					(size 1.27 1.27)
				)
			)
		)
		(property "Value" ""
			(at 0 0 90)
			(layer "F.Fab")
			(effects
				(font
					(size 1.27 1.27)
				)
			)
		)
		(duplicate_pad_numbers_are_jumpers no)
		(fp_line
			(start 0.7874 -0.4064)
			(end 0.7874 0.4064)
			(stroke
				(width 0.1524)
				(type default)
			)
			(layer "F.SilkS")
		)
		(fp_line
			(start -0.7874 -0.4064)
			(end 0.7874 -0.4064)
			(stroke
				(width 0.1524)
				(type default)
			)
			(layer "F.SilkS")
		)
		(fp_line
			(start 0.7874 0.4064)
			(end -0.7874 0.4064)
			(stroke
				(width 0.1524)
				(type default)
			)
			(layer "F.SilkS")
		)
		(fp_line
			(start -0.7874 0.4064)
			(end -0.7874 -0.4064)
			(stroke
				(width 0.1524)
				(type default)
			)
			(layer "F.SilkS")
		)
		(fp_line
			(start -0.12065 -0.305054)
			(end -0.12065 -0.2794)
			(stroke
				(width 0.1)
				(type default)
			)
			(layer "F.Fab")
		)
		(fp_line
			(start -0.67945 -0.305054)
			(end -0.12065 -0.305054)
			(stroke
				(width 0.1)
				(type default)
			)
			(layer "F.Fab")
		)
		(fp_line
			(start 0.67945 -0.3048)
			(end 0.67945 0.3048)
			(stroke
				(width 0.1)
				(type default)
			)
			(layer "F.Fab")
		)
		(fp_line
			(start 0.12065 -0.3048)
			(end 0.67945 -0.3048)
			(stroke
				(width 0.1)
				(type default)
			)
			(layer "F.Fab")
		)
		(fp_line
			(start 0.12065 -0.2794)
			(end 0.12065 -0.3048)
			(stroke
				(width 0.1)
				(type default)
			)
			(layer "F.Fab")
		)
		(fp_line
			(start -0.12065 -0.2794)
			(end 0.12065 -0.2794)
			(stroke
				(width 0.1)
				(type default)
			)
			(layer "F.Fab")
		)
		(fp_line
			(start 0.120396 0.2794)
			(end -0.12065 0.2794)
			(stroke
				(width 0.1)
				(type default)
			)
			(layer "F.Fab")
		)
		(fp_line
			(start -0.12065 0.2794)
			(end -0.12065 0.3048)
			(stroke
				(width 0.1)
				(type default)
			)
			(layer "F.Fab")
		)
		(fp_line
			(start 0.67945 0.3048)
			(end 0.120396 0.3048)
			(stroke
				(width 0.1)
				(type default)
			)
			(layer "F.Fab")
		)
		(fp_line
			(start 0.120396 0.3048)
			(end 0.120396 0.2794)
			(stroke
				(width 0.1)
				(type default)
			)
			(layer "F.Fab")
		)
		(fp_line
			(start -0.12065 0.3048)
			(end -0.67945 0.3048)
			(stroke
				(width 0.1)
				(type default)
			)
			(layer "F.Fab")
		)
		(fp_line
			(start -0.67945 0.3048)
			(end -0.67945 -0.305054)
			(stroke
				(width 0.1)
				(type default)
			)
			(layer "F.Fab")
		)
		(pad "1" smd circle
			(at -0.40005 0 90)
			(size 0 0)
			(layers "F.Cu" "F.Mask" "F.Paste")
			(net "P3V3_AUX")
		)
		(pad "2" smd circle
			(at 0.40005 0 90)
			(size 0 0)
			(layers "F.Cu" "F.Mask" "F.Paste")
			(net "GND")
		)
	)
	(footprint ""
		(layer "F.Cu")
		(at 66.022982 -36.906708 90)
		(property "Reference" "R4059"
			(at 0 0 90)
			(layer "F.SilkS")
			(hide yes)
			(effects
				(font
					(size 1.27 1.27)
				)
			)
		)
		(property "Value" ""
			(at 0 0 90)
			(layer "F.Fab")
			(effects
				(font
					(size 1.27 1.27)
				)
			)
		)
		(duplicate_pad_numbers_are_jumpers no)
		(fp_line
			(start 0.7874 -0.4064)
			(end 0.7874 0.4064)
			(stroke
				(width 0.1524)
				(type default)
			)
			(layer "F.SilkS")
		)
		(fp_line
			(start -0.7874 -0.4064)
			(end 0.7874 -0.4064)
			(stroke
				(width 0.1524)
				(type default)
			)
			(layer "F.SilkS")
		)
		(fp_line
			(start 0.7874 0.4064)
			(end -0.7874 0.4064)
			(stroke
				(width 0.1524)
				(type default)
			)
			(layer "F.SilkS")
		)
		(fp_line
			(start -0.7874 0.4064)
			(end -0.7874 -0.4064)
			(stroke
				(width 0.1524)
				(type default)
			)
			(layer "F.SilkS")
		)
		(fp_line
			(start -0.12065 -0.305054)
			(end -0.12065 -0.2794)
			(stroke
				(width 0.1)
				(type default)
			)
			(layer "F.Fab")
		)
		(fp_line
			(start -0.67945 -0.305054)
			(end -0.12065 -0.305054)
			(stroke
				(width 0.1)
				(type default)
			)
			(layer "F.Fab")
		)
		(fp_line
			(start 0.67945 -0.3048)
			(end 0.67945 0.3048)
			(stroke
				(width 0.1)
				(type default)
			)
			(layer "F.Fab")
		)
		(fp_line
			(start 0.12065 -0.3048)
			(end 0.67945 -0.3048)
			(stroke
				(width 0.1)
				(type default)
			)
			(layer "F.Fab")
		)
		(fp_line
			(start 0.12065 -0.2794)
			(end 0.12065 -0.3048)
			(stroke
				(width 0.1)
				(type default)
			)
			(layer "F.Fab")
		)
		(fp_line
			(start -0.12065 -0.2794)
			(end 0.12065 -0.2794)
			(stroke
				(width 0.1)
				(type default)
			)
			(layer "F.Fab")
		)
		(fp_line
			(start 0.120396 0.2794)
			(end -0.12065 0.2794)
			(stroke
				(width 0.1)
				(type default)
			)
			(layer "F.Fab")
		)
		(fp_line
			(start -0.12065 0.2794)
			(end -0.12065 0.3048)
			(stroke
				(width 0.1)
				(type default)
			)
			(layer "F.Fab")
		)
		(fp_line
			(start 0.67945 0.3048)
			(end 0.120396 0.3048)
			(stroke
				(width 0.1)
				(type default)
			)
			(layer "F.Fab")
		)
		(fp_line
			(start 0.120396 0.3048)
			(end 0.120396 0.2794)
			(stroke
				(width 0.1)
				(type default)
			)
			(layer "F.Fab")
		)
		(fp_line
			(start -0.12065 0.3048)
			(end -0.67945 0.3048)
			(stroke
				(width 0.1)
				(type default)
			)
			(layer "F.Fab")
		)
		(fp_line
			(start -0.67945 0.3048)
			(end -0.67945 -0.305054)
			(stroke
				(width 0.1)
				(type default)
			)
			(layer "F.Fab")
		)
		(pad "1" smd circle
			(at -0.40005 0 90)
			(size 0 0)
			(layers "F.Cu" "F.Mask" "F.Paste")
			(net "HP_LVC3_OCP_V3_2_EN")
		)
		(pad "2" smd circle
			(at 0.40005 0 90)
			(size 0 0)
			(layers "F.Cu" "F.Mask" "F.Paste")
			(net "P12V_OCP_EN_2_R")
		)
	)
	(footprint ""
		(layer "F.Cu")
		(at 64.185038 -402.371052 -90)
		(property "Reference" "C721"
			(at 0 0 270)
			(layer "F.SilkS")
			(hide yes)
			(effects
				(font
					(size 1.27 1.27)
				)
			)
		)
		(property "Value" ""
			(at 0 0 270)
			(layer "F.Fab")
			(effects
				(font
					(size 1.27 1.27)
				)
			)
		)
		(duplicate_pad_numbers_are_jumpers no)
		(fp_line
			(start -0.299974 0.150114)
			(end -0.299974 -0.150114)
			(stroke
				(width 0.1)
				(type default)
			)
			(layer "F.Fab")
		)
		(fp_line
			(start 0.299974 0.150114)
			(end -0.299974 0.150114)
			(stroke
				(width 0.1)
				(type default)
			)
			(layer "F.Fab")
		)
		(fp_line
			(start -0.299974 -0.150114)
			(end 0.299974 -0.150114)
			(stroke
				(width 0.1)
				(type default)
			)
			(layer "F.Fab")
		)
		(fp_line
			(start 0.299974 -0.150114)
			(end 0.299974 0.150114)
			(stroke
				(width 0.1)
				(type default)
			)
			(layer "F.Fab")
		)
		(pad "1" smd rect
			(at -0.2667 0 270)
			(size 0.3048 0.381)
			(layers "F.Cu" "F.Mask" "F.Paste")
			(net "P5E_CPU1_PE0_TX_C_DP<10>")
		)
		(pad "2" smd rect
			(at 0.2667 0 270)
			(size 0.3048 0.381)
			(layers "F.Cu" "F.Mask" "F.Paste")
			(net "P5E_CPU1_PE0_TX_DP<10>")
		)
	)
)
